#ISCELL
  logical_power cad_note *
  *
#ISCELL
  mstr_misc dns *
  *
#ISCELL
  pure_quanta quanta_title_block_c *
  *
#CELL
  pure_quanta lcmxo3lf9400c5bg484c *
  page313_i1
#ISCELL
  standard offpage *
  page313_i10
#ISCELL
  standard offpage *
  page313_i100
#ISCELL
  standard offpage *
  page313_i104
#ISCELL
  standard offpage *
  page313_i105
#ISCELL
  standard offpage *
  page313_i11
#CELL
  pure_quanta q_res *
  page313_i115
#ISCELL
  standard offpage *
  page313_i12
#ISCELL
  logical_power universal_gnd *
  page313_i123
#ISCELL
  logical_power universal_power *
  page313_i124
#ISCELL
  logical_power universal_gnd *
  page313_i125
#CELL
  pure_quanta q_cap *
  page313_i126
#CELL
  pure_quanta q_osc4p *
  page313_i127
#ISCELL
  logical_power universal_power *
  page313_i128
#CELL
  pure_quanta q_res *
  page313_i129
#ISCELL
  standard offpage *
  page313_i13
#ISCELL
  standard offpage *
  page313_i130
#ISCELL
  standard offpage *
  page313_i131
#ISCELL
  standard offpage *
  page313_i133
#ISCELL
  standard offpage *
  page313_i134
#ISCELL
  standard offpage *
  page313_i135
#ISCELL
  standard offpage *
  page313_i14
#ISCELL
  standard offpage *
  page313_i144
#ISCELL
  standard offpage *
  page313_i145
#ISCELL
  standard offpage *
  page313_i146
#CELL
  pure_quanta q_res *
  page313_i147
#ISCELL
  standard offpage *
  page313_i148
#ISCELL
  standard offpage *
  page313_i149
#ISCELL
  standard offpage *
  page313_i15
#ISCELL
  standard offpage *
  page313_i150
#ISCELL
  standard offpage *
  page313_i155
#ISCELL
  standard offpage *
  page313_i156
#ISCELL
  standard offpage *
  page313_i157
#ISCELL
  standard offpage *
  page313_i158
#CELL
  pure_quanta q_res *
  page313_i159
#ISCELL
  standard offpage *
  page313_i16
#CELL
  pure_quanta q_res *
  page313_i160
#ISCELL
  standard offpage *
  page313_i161
#ISCELL
  standard offpage *
  page313_i162
#ISCELL
  standard offpage *
  page313_i163
#ISCELL
  standard offpage *
  page313_i164
#ISCELL
  standard offpage *
  page313_i165
#CELL
  pure_quanta q_res *
  page313_i166
#CELL
  pure_quanta q_res *
  page313_i167
#ISCELL
  standard offpage *
  page313_i168
#ISCELL
  standard offpage *
  page313_i169
#ISCELL
  standard offpage *
  page313_i17
#ISCELL
  standard offpage *
  page313_i170
#ISCELL
  standard offpage *
  page313_i171
#ISCELL
  standard offpage *
  page313_i172
#ISCELL
  standard offpage *
  page313_i173
#ISCELL
  standard offpage *
  page313_i174
#CELL
  pure_quanta q_res *
  page313_i175
#CELL
  pure_quanta q_res *
  page313_i176
#ISCELL
  standard offpage *
  page313_i177
#ISCELL
  standard offpage *
  page313_i178
#ISCELL
  standard offpage *
  page313_i179
#ISCELL
  standard offpage *
  page313_i18
#CELL
  pure_quanta q_res *
  page313_i180
#ISCELL
  standard offpage *
  page313_i181
#ISCELL
  standard offpage *
  page313_i182
#CELL
  pure_quanta q_res *
  page313_i183
#ISCELL
  standard offpage *
  page313_i184
#ISCELL
  standard offpage *
  page313_i185
#ISCELL
  standard offpage *
  page313_i186
#ISCELL
  standard offpage *
  page313_i188
#ISCELL
  standard offpage *
  page313_i189
#ISCELL
  standard offpage *
  page313_i19
#CELL
  pure_quanta q_res *
  page313_i190
#ISCELL
  standard offpage *
  page313_i193
#CELL
  pure_quanta q_res *
  page313_i194
#ISCELL
  standard offpage *
  page313_i195
#ISCELL
  standard offpage *
  page313_i196
#ISCELL
  standard offpage *
  page313_i199
#ISCELL
  standard offpage *
  page313_i20
#CELL
  pure_quanta q_res *
  page313_i200
#ISCELL
  standard offpage *
  page313_i201
#ISCELL
  standard offpage *
  page313_i202
#ISCELL
  standard offpage *
  page313_i205
#CELL
  pure_quanta q_res *
  page313_i206
#ISCELL
  standard offpage *
  page313_i207
#ISCELL
  standard offpage *
  page313_i208
#ISCELL
  standard offpage *
  page313_i21
#ISCELL
  standard offpage *
  page313_i210
#CELL
  pure_quanta q_res *
  page313_i211
#ISCELL
  standard offpage *
  page313_i212
#ISCELL
  standard offpage *
  page313_i213
#ISCELL
  standard offpage *
  page313_i214
#ISCELL
  standard offpage *
  page313_i215
#ISCELL
  standard offpage *
  page313_i216
#ISCELL
  standard offpage *
  page313_i22
#ISCELL
  standard offpage *
  page313_i23
#ISCELL
  standard offpage *
  page313_i24
#ISCELL
  standard offpage *
  page313_i25
#ISCELL
  standard offpage *
  page313_i26
#ISCELL
  standard offpage *
  page313_i27
#ISCELL
  standard offpage *
  page313_i28
#ISCELL
  standard offpage *
  page313_i29
#ISCELL
  standard offpage *
  page313_i3
#ISCELL
  standard offpage *
  page313_i30
#ISCELL
  standard offpage *
  page313_i31
#ISCELL
  standard offpage *
  page313_i32
#ISCELL
  standard offpage *
  page313_i33
#ISCELL
  standard offpage *
  page313_i34
#ISCELL
  standard offpage *
  page313_i35
#ISCELL
  standard offpage *
  page313_i36
#ISCELL
  standard offpage *
  page313_i37
#ISCELL
  standard offpage *
  page313_i38
#ISCELL
  standard offpage *
  page313_i39
#ISCELL
  standard offpage *
  page313_i4
#ISCELL
  standard offpage *
  page313_i40
#ISCELL
  standard offpage *
  page313_i41
#ISCELL
  standard offpage *
  page313_i42
#ISCELL
  standard offpage *
  page313_i43
#ISCELL
  standard offpage *
  page313_i44
#ISCELL
  standard offpage *
  page313_i45
#ISCELL
  standard offpage *
  page313_i46
#ISCELL
  standard offpage *
  page313_i47
#ISCELL
  standard offpage *
  page313_i48
#ISCELL
  standard offpage *
  page313_i49
#ISCELL
  standard offpage *
  page313_i5
#ISCELL
  standard offpage *
  page313_i50
#ISCELL
  standard offpage *
  page313_i51
#ISCELL
  standard offpage *
  page313_i52
#ISCELL
  standard offpage *
  page313_i53
#ISCELL
  standard offpage *
  page313_i54
#ISCELL
  standard offpage *
  page313_i55
#ISCELL
  standard offpage *
  page313_i56
#ISCELL
  standard offpage *
  page313_i57
#ISCELL
  standard offpage *
  page313_i58
#ISCELL
  standard offpage *
  page313_i59
#ISCELL
  standard offpage *
  page313_i6
#ISCELL
  standard offpage *
  page313_i60
#ISCELL
  standard offpage *
  page313_i61
#ISCELL
  standard offpage *
  page313_i62
#ISCELL
  standard offpage *
  page313_i63
#ISCELL
  standard offpage *
  page313_i64
#ISCELL
  standard offpage *
  page313_i65
#ISCELL
  standard offpage *
  page313_i7
#ISCELL
  standard offpage *
  page313_i76
#ISCELL
  standard offpage *
  page313_i77
#ISCELL
  standard offpage *
  page313_i78
#ISCELL
  standard offpage *
  page313_i79
#ISCELL
  standard offpage *
  page313_i8
#CELL
  pure_quanta q_res *
  page313_i83
#CELL
  pure_quanta q_res *
  page313_i84
#CELL
  pure_quanta q_res *
  page313_i85
#CELL
  pure_quanta q_res *
  page313_i86
#ISCELL
  standard offpage *
  page313_i87
#ISCELL
  standard offpage *
  page313_i88
#ISCELL
  standard offpage *
  page313_i9
#ISCELL
  standard offpage *
  page313_i99
